(kicad_pcb
	(version 20260206)
	(generator "pcbnew")
	(generator_version "10.0")
	(general
		(thickness 1.6)
		(legacy_teardrops no)
	)
	(paper "A4")
	(title_block
		(title "01162023_DA0F0TEBIF0_F0T_Expander_BD_F_brd_V02_OCP.brd")
		(comment 1 "Grand Teton / footprints 7369-7376 of 9728")
	)
	(layers
		(0 "F.Cu" signal "TOP")
		(4 "In1.Cu" signal "GND")
		(6 "In2.Cu" signal "VCC")
		(8 "In3.Cu" signal "VCC1")
		(10 "In4.Cu" signal "GND1")
		(12 "In5.Cu" signal "IN1")
		(14 "In6.Cu" signal "GND2")
		(16 "In7.Cu" signal "IN2")
		(18 "In8.Cu" signal "GND3")
		(20 "In9.Cu" signal "IN3")
		(22 "In10.Cu" signal "GND4")
		(24 "In11.Cu" signal "IN4")
		(26 "In12.Cu" signal "GND5")
		(28 "In13.Cu" signal "IN5")
		(30 "In14.Cu" signal "GND6")
		(32 "In15.Cu" signal "IN6")
		(34 "In16.Cu" signal "GND7")
		(2 "B.Cu" signal "BOTTOM")
		(9 "F.Adhes" user "F.Adhesive")
		(11 "B.Adhes" user "B.Adhesive")
		(13 "F.Paste" user "Package Geometry/Pastemask Top")
		(15 "B.Paste" user "Package Geometry/Pastemask Bottom")
		(5 "F.SilkS" user "Ref Des/Silkscreen Top")
		(7 "B.SilkS" user "Ref Des/Silkscreen Bottom")
		(1 "F.Mask" user "Board Geometry/Soldermask Top")
		(3 "B.Mask" user "Board Geometry/Soldermask Bottom")
		(17 "Dwgs.User" user "User.Drawings")
		(19 "Cmts.User" user "User.Comments")
		(21 "Eco1.User" user "User.Eco1")
		(23 "Eco2.User" user "User.Eco2")
		(25 "Edge.Cuts" user "Board Geometry/Outline")
		(27 "Margin" user)
		(31 "F.CrtYd" user "Package Geometry/Place Bound Top")
		(29 "B.CrtYd" user "Package Geometry/Place Bound Bottom")
		(35 "F.Fab" user "Ref Des/Assembly Top")
		(33 "B.Fab" user "Ref Des/Assembly Bottom")
	)
	(footprint ""
		(layer "B.Cu")
		(at 219.92082 -220.762068)
		(property "Reference" "R6802"
			(at 0 0 0)
			(layer "B.SilkS")
			(hide yes)
			(effects
				(font
					(size 1.27 1.27)
				)
				(justify mirror)
			)
		)
		(property "Value" ""
			(at 0 0 0)
			(layer "B.Fab")
			(effects
				(font
					(size 1.27 1.27)
				)
				(justify mirror)
			)
		)
		(duplicate_pad_numbers_are_jumpers no)
		(fp_line
			(start -0.7874 -0.4064)
			(end -0.7874 0.4064)
			(stroke
				(width 0.1524)
				(type default)
			)
			(layer "B.SilkS")
		)
		(fp_line
			(start -0.7874 0.4064)
			(end 0.7874 0.4064)
			(stroke
				(width 0.1524)
				(type default)
			)
			(layer "B.SilkS")
		)
		(fp_line
			(start 0.7874 -0.4064)
			(end -0.7874 -0.4064)
			(stroke
				(width 0.1524)
				(type default)
			)
			(layer "B.SilkS")
		)
		(fp_line
			(start 0.7874 0.4064)
			(end 0.7874 -0.4064)
			(stroke
				(width 0.1524)
				(type default)
			)
			(layer "B.SilkS")
		)
		(fp_line
			(start -0.67945 -0.3048)
			(end -0.67945 0.3048)
			(stroke
				(width 0.1)
				(type default)
			)
			(layer "B.Fab")
		)
		(fp_line
			(start -0.67945 0.3048)
			(end -0.120396 0.3048)
			(stroke
				(width 0.1)
				(type default)
			)
			(layer "B.Fab")
		)
		(fp_line
			(start -0.12065 -0.3048)
			(end -0.67945 -0.3048)
			(stroke
				(width 0.1)
				(type default)
			)
			(layer "B.Fab")
		)
		(fp_line
			(start -0.12065 -0.2794)
			(end -0.12065 -0.3048)
			(stroke
				(width 0.1)
				(type default)
			)
			(layer "B.Fab")
		)
		(fp_line
			(start -0.120396 0.2794)
			(end 0.12065 0.2794)
			(stroke
				(width 0.1)
				(type default)
			)
			(layer "B.Fab")
		)
		(fp_line
			(start -0.120396 0.3048)
			(end -0.120396 0.2794)
			(stroke
				(width 0.1)
				(type default)
			)
			(layer "B.Fab")
		)
		(fp_line
			(start 0.12065 -0.305054)
			(end 0.12065 -0.2794)
			(stroke
				(width 0.1)
				(type default)
			)
			(layer "B.Fab")
		)
		(fp_line
			(start 0.12065 -0.2794)
			(end -0.12065 -0.2794)
			(stroke
				(width 0.1)
				(type default)
			)
			(layer "B.Fab")
		)
		(fp_line
			(start 0.12065 0.2794)
			(end 0.12065 0.3048)
			(stroke
				(width 0.1)
				(type default)
			)
			(layer "B.Fab")
		)
		(fp_line
			(start 0.12065 0.3048)
			(end 0.67945 0.3048)
			(stroke
				(width 0.1)
				(type default)
			)
			(layer "B.Fab")
		)
		(fp_line
			(start 0.67945 -0.305054)
			(end 0.12065 -0.305054)
			(stroke
				(width 0.1)
				(type default)
			)
			(layer "B.Fab")
		)
		(fp_line
			(start 0.67945 0.3048)
			(end 0.67945 -0.305054)
			(stroke
				(width 0.1)
				(type default)
			)
			(layer "B.Fab")
		)
		(pad "1" smd circle
			(at 0.40005 0 180)
			(size 0 0)
			(layers "B.Cu" "B.Mask" "B.Paste")
			(net "SMB_BIC_FPGA_R2_SCL")
		)
		(pad "2" smd circle
			(at -0.40005 0 180)
			(size 0 0)
			(layers "B.Cu" "B.Mask" "B.Paste")
			(net "SMB_BIC_FPGA_SCL")
		)
	)
	(footprint ""
		(layer "B.Cu")
		(at 146.685254 -207.784192 -90)
		(property "Reference" "R981"
			(at 0 0 90)
			(layer "B.SilkS")
			(hide yes)
			(effects
				(font
					(size 1.27 1.27)
				)
				(justify mirror)
			)
		)
		(property "Value" ""
			(at 0 0 90)
			(layer "B.Fab")
			(effects
				(font
					(size 1.27 1.27)
				)
				(justify mirror)
			)
		)
		(duplicate_pad_numbers_are_jumpers no)
		(fp_line
			(start -0.7874 0.4064)
			(end 0.7874 0.4064)
			(stroke
				(width 0.1524)
				(type default)
			)
			(layer "B.SilkS")
		)
		(fp_line
			(start 0.7874 0.4064)
			(end 0.7874 -0.4064)
			(stroke
				(width 0.1524)
				(type default)
			)
			(layer "B.SilkS")
		)
		(fp_line
			(start -0.7874 -0.4064)
			(end -0.7874 0.4064)
			(stroke
				(width 0.1524)
				(type default)
			)
			(layer "B.SilkS")
		)
		(fp_line
			(start 0.7874 -0.4064)
			(end -0.7874 -0.4064)
			(stroke
				(width 0.1524)
				(type default)
			)
			(layer "B.SilkS")
		)
		(fp_line
			(start -0.67945 0.3048)
			(end -0.120396 0.3048)
			(stroke
				(width 0.1)
				(type default)
			)
			(layer "B.Fab")
		)
		(fp_line
			(start -0.120396 0.3048)
			(end -0.120396 0.2794)
			(stroke
				(width 0.1)
				(type default)
			)
			(layer "B.Fab")
		)
		(fp_line
			(start 0.12065 0.3048)
			(end 0.67945 0.3048)
			(stroke
				(width 0.1)
				(type default)
			)
			(layer "B.Fab")
		)
		(fp_line
			(start 0.67945 0.3048)
			(end 0.67945 -0.305054)
			(stroke
				(width 0.1)
				(type default)
			)
			(layer "B.Fab")
		)
		(fp_line
			(start -0.120396 0.2794)
			(end 0.12065 0.2794)
			(stroke
				(width 0.1)
				(type default)
			)
			(layer "B.Fab")
		)
		(fp_line
			(start 0.12065 0.2794)
			(end 0.12065 0.3048)
			(stroke
				(width 0.1)
				(type default)
			)
			(layer "B.Fab")
		)
		(fp_line
			(start -0.12065 -0.2794)
			(end -0.12065 -0.3048)
			(stroke
				(width 0.1)
				(type default)
			)
			(layer "B.Fab")
		)
		(fp_line
			(start 0.12065 -0.2794)
			(end -0.12065 -0.2794)
			(stroke
				(width 0.1)
				(type default)
			)
			(layer "B.Fab")
		)
		(fp_line
			(start -0.67945 -0.3048)
			(end -0.67945 0.3048)
			(stroke
				(width 0.1)
				(type default)
			)
			(layer "B.Fab")
		)
		(fp_line
			(start -0.12065 -0.3048)
			(end -0.67945 -0.3048)
			(stroke
				(width 0.1)
				(type default)
			)
			(layer "B.Fab")
		)
		(fp_line
			(start 0.12065 -0.305054)
			(end 0.12065 -0.2794)
			(stroke
				(width 0.1)
				(type default)
			)
			(layer "B.Fab")
		)
		(fp_line
			(start 0.67945 -0.305054)
			(end 0.12065 -0.305054)
			(stroke
				(width 0.1)
				(type default)
			)
			(layer "B.Fab")
		)
		(pad "1" smd circle
			(at 0.40005 0 90)
			(size 0 0)
			(layers "B.Cu" "B.Mask" "B.Paste")
			(net "UART_PEX1_CLI_BUF_R_RX")
		)
		(pad "2" smd circle
			(at -0.40005 0 90)
			(size 0 0)
			(layers "B.Cu" "B.Mask" "B.Paste")
			(net "UART_PEX1_CLI_BUF_RX")
		)
	)
	(footprint ""
		(layer "B.Cu")
		(at 405.100028 -299.699934 -90)
		(property "Reference" "C1973"
			(at 0 0 90)
			(layer "B.SilkS")
			(hide yes)
			(effects
				(font
					(size 1.27 1.27)
				)
				(justify mirror)
			)
		)
		(property "Value" ""
			(at 0 0 90)
			(layer "B.Fab")
			(effects
				(font
					(size 1.27 1.27)
				)
				(justify mirror)
			)
		)
		(duplicate_pad_numbers_are_jumpers no)
		(fp_line
			(start -0.299974 0.150114)
			(end 0.299974 0.150114)
			(stroke
				(width 0.1)
				(type default)
			)
			(layer "B.Fab")
		)
		(fp_line
			(start 0.299974 0.150114)
			(end 0.299974 -0.150114)
			(stroke
				(width 0.1)
				(type default)
			)
			(layer "B.Fab")
		)
		(fp_line
			(start -0.299974 -0.150114)
			(end -0.299974 0.150114)
			(stroke
				(width 0.1)
				(type default)
			)
			(layer "B.Fab")
		)
		(fp_line
			(start 0.299974 -0.150114)
			(end -0.299974 -0.150114)
			(stroke
				(width 0.1)
				(type default)
			)
			(layer "B.Fab")
		)
		(pad "1" smd rect
			(at 0.2667 0 90)
			(size 0.3048 0.381)
			(layers "B.Cu" "B.Mask" "B.Paste")
			(net "P0V8_SERDES_VDDA_PEX3")
		)
		(pad "2" smd rect
			(at -0.2667 0 90)
			(size 0.3048 0.381)
			(layers "B.Cu" "B.Mask" "B.Paste")
			(net "GND")
		)
	)
	(footprint ""
		(layer "B.Cu")
		(at 12.709398 -270.452596 180)
		(property "Reference" "C4221"
			(at 0 0 0)
			(layer "B.SilkS")
			(hide yes)
			(effects
				(font
					(size 1.27 1.27)
				)
				(justify mirror)
			)
		)
		(property "Value" ""
			(at 0 0 0)
			(layer "B.Fab")
			(effects
				(font
					(size 1.27 1.27)
				)
				(justify mirror)
			)
		)
		(duplicate_pad_numbers_are_jumpers no)
		(fp_line
			(start 1.2954 0.5842)
			(end 1.2954 -0.5842)
			(stroke
				(width 0.1524)
				(type default)
			)
			(layer "B.SilkS")
		)
		(fp_line
			(start 1.2954 -0.5842)
			(end -1.2954 -0.5842)
			(stroke
				(width 0.1524)
				(type default)
			)
			(layer "B.SilkS")
		)
		(fp_line
			(start -1.2954 0.5842)
			(end 1.2954 0.5842)
			(stroke
				(width 0.1524)
				(type default)
			)
			(layer "B.SilkS")
		)
		(fp_line
			(start -1.2954 -0.5842)
			(end -1.2954 0.5842)
			(stroke
				(width 0.1524)
				(type default)
			)
			(layer "B.SilkS")
		)
		(fp_line
			(start 1.1938 0.4064)
			(end 1.1938 -0.4064)
			(stroke
				(width 0.1)
				(type default)
			)
			(layer "B.Fab")
		)
		(fp_line
			(start 1.1938 -0.4064)
			(end 0.8636 -0.4064)
			(stroke
				(width 0.1)
				(type default)
			)
			(layer "B.Fab")
		)
		(fp_line
			(start 0.8636 0.4572)
			(end 0.8636 0.4064)
			(stroke
				(width 0.1)
				(type default)
			)
			(layer "B.Fab")
		)
		(fp_line
			(start 0.8636 0.4064)
			(end 1.1938 0.4064)
			(stroke
				(width 0.1)
				(type default)
			)
			(layer "B.Fab")
		)
		(fp_line
			(start 0.8636 -0.4064)
			(end 0.8636 -0.4572)
			(stroke
				(width 0.1)
				(type default)
			)
			(layer "B.Fab")
		)
		(fp_line
			(start 0.8636 -0.4572)
			(end -0.8636 -0.4572)
			(stroke
				(width 0.1)
				(type default)
			)
			(layer "B.Fab")
		)
		(fp_line
			(start -0.8636 0.4572)
			(end 0.8636 0.4572)
			(stroke
				(width 0.1)
				(type default)
			)
			(layer "B.Fab")
		)
		(fp_line
			(start -0.8636 0.4064)
			(end -0.8636 0.4572)
			(stroke
				(width 0.1)
				(type default)
			)
			(layer "B.Fab")
		)
		(fp_line
			(start -0.8636 -0.4064)
			(end -1.1938 -0.4064)
			(stroke
				(width 0.1)
				(type default)
			)
			(layer "B.Fab")
		)
		(fp_line
			(start -0.8636 -0.4572)
			(end -0.8636 -0.4064)
			(stroke
				(width 0.1)
				(type default)
			)
			(layer "B.Fab")
		)
		(fp_line
			(start -1.1938 0.4064)
			(end -0.8636 0.4064)
			(stroke
				(width 0.1)
				(type default)
			)
			(layer "B.Fab")
		)
		(fp_line
			(start -1.1938 -0.4064)
			(end -1.1938 0.4064)
			(stroke
				(width 0.1)
				(type default)
			)
			(layer "B.Fab")
		)
		(pad "1" smd rect
			(at 0.7366 0 90)
			(size 0.7112 0.8128)
			(layers "B.Cu" "B.Mask" "B.Paste")
			(net "P1V25_PEX0")
		)
		(pad "2" smd rect
			(at -0.7366 0 90)
			(size 0.7112 0.8128)
			(layers "B.Cu" "B.Mask" "B.Paste")
			(net "GND")
		)
	)
	(footprint ""
		(layer "B.Cu")
		(at 213.706456 -226.441762 180)
		(property "Reference" "R4871"
			(at 0 0 0)
			(layer "B.SilkS")
			(hide yes)
			(effects
				(font
					(size 1.27 1.27)
				)
				(justify mirror)
			)
		)
		(property "Value" ""
			(at 0 0 0)
			(layer "B.Fab")
			(effects
				(font
					(size 1.27 1.27)
				)
				(justify mirror)
			)
		)
		(duplicate_pad_numbers_are_jumpers no)
		(fp_line
			(start 0.7874 0.4064)
			(end 0.7874 -0.4064)
			(stroke
				(width 0.1524)
				(type default)
			)
			(layer "B.SilkS")
		)
		(fp_line
			(start 0.7874 -0.4064)
			(end -0.7874 -0.4064)
			(stroke
				(width 0.1524)
				(type default)
			)
			(layer "B.SilkS")
		)
		(fp_line
			(start -0.7874 0.4064)
			(end 0.7874 0.4064)
			(stroke
				(width 0.1524)
				(type default)
			)
			(layer "B.SilkS")
		)
		(fp_line
			(start -0.7874 -0.4064)
			(end -0.7874 0.4064)
			(stroke
				(width 0.1524)
				(type default)
			)
			(layer "B.SilkS")
		)
		(fp_line
			(start 0.67945 0.3048)
			(end 0.67945 -0.305054)
			(stroke
				(width 0.1)
				(type default)
			)
			(layer "B.Fab")
		)
		(fp_line
			(start 0.67945 -0.305054)
			(end 0.12065 -0.305054)
			(stroke
				(width 0.1)
				(type default)
			)
			(layer "B.Fab")
		)
		(fp_line
			(start 0.12065 0.3048)
			(end 0.67945 0.3048)
			(stroke
				(width 0.1)
				(type default)
			)
			(layer "B.Fab")
		)
		(fp_line
			(start 0.12065 0.2794)
			(end 0.12065 0.3048)
			(stroke
				(width 0.1)
				(type default)
			)
			(layer "B.Fab")
		)
		(fp_line
			(start 0.12065 -0.2794)
			(end -0.12065 -0.2794)
			(stroke
				(width 0.1)
				(type default)
			)
			(layer "B.Fab")
		)
		(fp_line
			(start 0.12065 -0.305054)
			(end 0.12065 -0.2794)
			(stroke
				(width 0.1)
				(type default)
			)
			(layer "B.Fab")
		)
		(fp_line
			(start -0.120396 0.3048)
			(end -0.120396 0.2794)
			(stroke
				(width 0.1)
				(type default)
			)
			(layer "B.Fab")
		)
		(fp_line
			(start -0.120396 0.2794)
			(end 0.12065 0.2794)
			(stroke
				(width 0.1)
				(type default)
			)
			(layer "B.Fab")
		)
		(fp_line
			(start -0.12065 -0.2794)
			(end -0.12065 -0.3048)
			(stroke
				(width 0.1)
				(type default)
			)
			(layer "B.Fab")
		)
		(fp_line
			(start -0.12065 -0.3048)
			(end -0.67945 -0.3048)
			(stroke
				(width 0.1)
				(type default)
			)
			(layer "B.Fab")
		)
		(fp_line
			(start -0.67945 0.3048)
			(end -0.120396 0.3048)
			(stroke
				(width 0.1)
				(type default)
			)
			(layer "B.Fab")
		)
		(fp_line
			(start -0.67945 -0.3048)
			(end -0.67945 0.3048)
			(stroke
				(width 0.1)
				(type default)
			)
			(layer "B.Fab")
		)
		(pad "1" smd circle
			(at 0.40005 0)
			(size 0 0)
			(layers "B.Cu" "B.Mask" "B.Paste")
			(net "P3V3_AUX")
		)
		(pad "2" smd circle
			(at -0.40005 0)
			(size 0 0)
			(layers "B.Cu" "B.Mask" "B.Paste")
			(net "SMB_FIO_SCL")
		)
	)
	(footprint ""
		(layer "B.Cu")
		(at 278.064214 -143.608552 180)
		(property "Reference" "C908"
			(at 0 0 0)
			(layer "B.SilkS")
			(hide yes)
			(effects
				(font
					(size 1.27 1.27)
				)
				(justify mirror)
			)
		)
		(property "Value" ""
			(at 0 0 0)
			(layer "B.Fab")
			(effects
				(font
					(size 1.27 1.27)
				)
				(justify mirror)
			)
		)
		(duplicate_pad_numbers_are_jumpers no)
		(fp_line
			(start 0.299974 0.150114)
			(end 0.299974 -0.150114)
			(stroke
				(width 0.1)
				(type default)
			)
			(layer "B.Fab")
		)
		(fp_line
			(start 0.299974 -0.150114)
			(end -0.299974 -0.150114)
			(stroke
				(width 0.1)
				(type default)
			)
			(layer "B.Fab")
		)
		(fp_line
			(start -0.299974 0.150114)
			(end 0.299974 0.150114)
			(stroke
				(width 0.1)
				(type default)
			)
			(layer "B.Fab")
		)
		(fp_line
			(start -0.299974 -0.150114)
			(end -0.299974 0.150114)
			(stroke
				(width 0.1)
				(type default)
			)
			(layer "B.Fab")
		)
		(pad "1" smd rect
			(at 0.2667 0)
			(size 0.3048 0.381)
			(layers "B.Cu" "B.Mask" "B.Paste")
			(net "P12V_NIC4")
		)
		(pad "2" smd rect
			(at -0.2667 0)
			(size 0.3048 0.381)
			(layers "B.Cu" "B.Mask" "B.Paste")
			(net "GND")
		)
	)
	(footprint ""
		(layer "B.Cu")
		(at 217.244422 -226.755452)
		(property "Reference" "R1490"
			(at 0 0 0)
			(layer "B.SilkS")
			(hide yes)
			(effects
				(font
					(size 1.27 1.27)
				)
				(justify mirror)
			)
		)
		(property "Value" ""
			(at 0 0 0)
			(layer "B.Fab")
			(effects
				(font
					(size 1.27 1.27)
				)
				(justify mirror)
			)
		)
		(duplicate_pad_numbers_are_jumpers no)
		(fp_line
			(start -0.7874 -0.4064)
			(end -0.7874 0.4064)
			(stroke
				(width 0.1524)
				(type default)
			)
			(layer "B.SilkS")
		)
		(fp_line
			(start -0.7874 0.4064)
			(end 0.7874 0.4064)
			(stroke
				(width 0.1524)
				(type default)
			)
			(layer "B.SilkS")
		)
		(fp_line
			(start 0.7874 -0.4064)
			(end -0.7874 -0.4064)
			(stroke
				(width 0.1524)
				(type default)
			)
			(layer "B.SilkS")
		)
		(fp_line
			(start 0.7874 0.4064)
			(end 0.7874 -0.4064)
			(stroke
				(width 0.1524)
				(type default)
			)
			(layer "B.SilkS")
		)
		(fp_line
			(start -0.67945 -0.3048)
			(end -0.67945 0.3048)
			(stroke
				(width 0.1)
				(type default)
			)
			(layer "B.Fab")
		)
		(fp_line
			(start -0.67945 0.3048)
			(end -0.120396 0.3048)
			(stroke
				(width 0.1)
				(type default)
			)
			(layer "B.Fab")
		)
		(fp_line
			(start -0.12065 -0.3048)
			(end -0.67945 -0.3048)
			(stroke
				(width 0.1)
				(type default)
			)
			(layer "B.Fab")
		)
		(fp_line
			(start -0.12065 -0.2794)
			(end -0.12065 -0.3048)
			(stroke
				(width 0.1)
				(type default)
			)
			(layer "B.Fab")
		)
		(fp_line
			(start -0.120396 0.2794)
			(end 0.12065 0.2794)
			(stroke
				(width 0.1)
				(type default)
			)
			(layer "B.Fab")
		)
		(fp_line
			(start -0.120396 0.3048)
			(end -0.120396 0.2794)
			(stroke
				(width 0.1)
				(type default)
			)
			(layer "B.Fab")
		)
		(fp_line
			(start 0.12065 -0.305054)
			(end 0.12065 -0.2794)
			(stroke
				(width 0.1)
				(type default)
			)
			(layer "B.Fab")
		)
		(fp_line
			(start 0.12065 -0.2794)
			(end -0.12065 -0.2794)
			(stroke
				(width 0.1)
				(type default)
			)
			(layer "B.Fab")
		)
		(fp_line
			(start 0.12065 0.2794)
			(end 0.12065 0.3048)
			(stroke
				(width 0.1)
				(type default)
			)
			(layer "B.Fab")
		)
		(fp_line
			(start 0.12065 0.3048)
			(end 0.67945 0.3048)
			(stroke
				(width 0.1)
				(type default)
			)
			(layer "B.Fab")
		)
		(fp_line
			(start 0.67945 -0.305054)
			(end 0.12065 -0.305054)
			(stroke
				(width 0.1)
				(type default)
			)
			(layer "B.Fab")
		)
		(fp_line
			(start 0.67945 0.3048)
			(end 0.67945 -0.305054)
			(stroke
				(width 0.1)
				(type default)
			)
			(layer "B.Fab")
		)
		(pad "1" smd circle
			(at 0.40005 0 180)
			(size 0 0)
			(layers "B.Cu" "B.Mask" "B.Paste")
			(net "SMB_FIO_SCL")
		)
		(pad "2" smd circle
			(at -0.40005 0 180)
			(size 0 0)
			(layers "B.Cu" "B.Mask" "B.Paste")
			(net "SMB_FIO_R1_SCL")
		)
	)
	(footprint ""
		(layer "B.Cu")
		(at 179.57038 -296.37482)
		(property "Reference" "C1393"
			(at 0 0 0)
			(layer "B.SilkS")
			(hide yes)
			(effects
				(font
					(size 1.27 1.27)
				)
				(justify mirror)
			)
		)
		(property "Value" ""
			(at 0 0 0)
			(layer "B.Fab")
			(effects
				(font
					(size 1.27 1.27)
				)
				(justify mirror)
			)
		)
		(duplicate_pad_numbers_are_jumpers no)
		(fp_line
			(start -0.299974 -0.150114)
			(end -0.299974 0.150114)
			(stroke
				(width 0.1)
				(type default)
			)
			(layer "B.Fab")
		)
		(fp_line
			(start -0.299974 0.150114)
			(end 0.299974 0.150114)
			(stroke
				(width 0.1)
				(type default)
			)
			(layer "B.Fab")
		)
		(fp_line
			(start 0.299974 -0.150114)
			(end -0.299974 -0.150114)
			(stroke
				(width 0.1)
				(type default)
			)
			(layer "B.Fab")
		)
		(fp_line
			(start 0.299974 0.150114)
			(end 0.299974 -0.150114)
			(stroke
				(width 0.1)
				(type default)
			)
			(layer "B.Fab")
		)
		(pad "1" smd rect
			(at 0.2667 0 180)
			(size 0.3048 0.381)
			(layers "B.Cu" "B.Mask" "B.Paste")
			(net "P0V8_PEX1")
		)
		(pad "2" smd rect
			(at -0.2667 0 180)
			(size 0.3048 0.381)
			(layers "B.Cu" "B.Mask" "B.Paste")
			(net "GND")
		)
	)
)
